FILE_TYPE = CONNECTIVITY;
{Allegro Design Entry HDL 17.2-2016 S081 (4005846) 1/11/2022}
"PAGE_NUMBER" = 137;
0"NC";
1"P1V05_PCH_AUX\g";
2"P3V3_AUX\g"PHYS_NET_NAME"P3V3_AUX"CDS_PHYS_NET_NAME"P3V3_AUX"VOLTAGE"3.3"PHYS_NET_NAME"P3V3_AUX"CDS_PHYS_NET_NAME"P3V3_AUX"VOLTAGE"3.3";
3"P3V3_AUX\g";
4"P3V3_AUX\g";
5"GND\g";
6"GND\g"PHYS_NET_NAME"GND"VOLTAGE"3.3"CDS_PHYS_NET_NAME"GND";
7"GND\g";
8"GND\g";
9"GND\g";
10"GND\g";
11"GND\g";
12"GND\g";
13"FM_JTAG_TCK_MUX_SEL"CDS_PHYS_NET_NAME"FM_JTAG_TCK_MUX_SEL";
14"JTAG_BMC_PCH_TCK"CDS_PHYS_NET_NAME"JTAG_BMC_PCH_TCK";
15"JTAG_BMC_CPU_TCK"CDS_PHYS_NET_NAME"JTAG_BMC_CPU_TCK";
16"PD_JTAG_BMC_NTRST_N";
17"FM_REMOTE_DEBUG_DET_R";
18"FM_BMC_EN_DET";
19"JTAG_DBP_CPU_GTL_TCK_R1"CDS_PHYS_NET_NAME"JTAG_DBP_CPU_GTL_TCK_R1";
20"JTAG_DBP_CPU_GTL_TCK"CDS_PHYS_NET_NAME"JTAG_DBP_CPU_GTL_TCK";
21"JTAG_DBP_TCK_PCH_R"CDS_PHYS_NET_NAME"JTAG_DBP_TCK_PCH_R";
22"JTAG_DBP_TCK_PCH";
23"JTAG_BMC_DBP_TCK"CDS_PHYS_NET_NAME"JTAG_BMC_DBP_TCK";
24"TP_JTAG_BMC_1B"CDS_PHYS_NET_NAME"TP_JTAG_BMC_1B";
25"TP_JTAG_BMC_4B"CDS_PHYS_NET_NAME"TP_JTAG_BMC_4B";
%"UNIVERSAL_GND"
"1","(-8175,-2025)","0","logical_power","I101";
;
CDS_LIB"logical_power"
HDL_POWER"GND";
"A"12;
%"Q_RES"
"2","(-8175,-1775)","2","pure_quanta","I102";
;
PART_NUMBER"CS21002FB06"
TOLERANCE"1%"
PACK_TYPE"0402LF"
MATERIAL"EMPTY"
WATTAGE"1/16W"
VALUE"1K"
$LOCATION"R3025"
CDS_LIB"pure_quanta"
CDS_LOCATION"R3025"
$SEC"1"
CDS_SEC"1";
"A"
$PN"1"17;
"B"
$PN"2"12;
%"Q_RES"
"2","(-7400,-2950)","0","pure_quanta","I103";
;
PART_NUMBER"CS21002FB06"
TOLERANCE"1%"
WATTAGE"1/16W"
PACK_TYPE"0402LF"
MATERIAL"CHIP"
VALUE"1K"
$LOCATION"R1374"
CDS_LIB"pure_quanta"
CDS_LOCATION"R1374"
$SEC"1"
CDS_SEC"1";
"A"
$PN"1"16;
"B"
$PN"2"11;
%"UNIVERSAL_GND"
"1","(-7400,-3225)","0","logical_power","I104";
;
HDL_POWER"GND"
CDS_LIB"logical_power";
"A"11;
%"Q_RES"
"2","(-7625,-2950)","0","pure_quanta","I105";
;
PART_NUMBER"CS21002FB06"
MATERIAL"CHIP"
WATTAGE"1/16W"
VALUE"1K"
TOLERANCE"1%"
PACK_TYPE"0402LF"
$LOCATION"R3027"
CDS_LIB"pure_quanta"
CDS_LOCATION"R3027"
$SEC"1"
CDS_SEC"1";
"A"
$PN"1"15;
"B"
$PN"2"11;
%"Q_RES"
"2","(-7850,-2950)","0","pure_quanta","I106";
;
PART_NUMBER"CS21002FB06"
VALUE"1K"
WATTAGE"1/16W"
TOLERANCE"1%"
MATERIAL"CHIP"
PACK_TYPE"0402LF"
$LOCATION"R3026"
CDS_LIB"pure_quanta"
CDS_LOCATION"R3026"
$SEC"1"
CDS_SEC"1";
"A"
$PN"1"14;
"B"
$PN"2"11;
%"UNIVERSAL_GND"
"1","(-8175,-2975)","0","logical_power","I107";
;
CDS_LIB"logical_power"
HDL_POWER"GND";
"A"10;
%"NC7SB3157"
"1","(-8600,-2475)","2","pure_quanta","I109";
;
PART_NUMBER"ALSB3157000"
MATERIAL"IC"
VALUE"NC7SB3157P6X"
$LOCATION"U85"
CDS_LMAN_SYM_OUTLINE"-150,50,150,-150"
CDS_LIB"pure_quanta"
PACK_TYPE"SMLF"
MANUF_PN"NC7SB3157P6X"
$LOCATION"U85"
CDS_LOCATION"U85"
$SEC"1"
CDS_SEC"1";
"S"
$PN"6"13;
"B0"
$PN"3"15;
"B1"
$PN"1"14;
"VCC"
$PN"5"4;
"GND"
$PN"2"10;
"A"
$PN"4"23;
%"Q_CAP"
"1","(-9175,-2075)","2","pure_quanta","I110";
;
PART_NUMBER"CH5104KEB02"
PACK_TYPE"C0402"
MATERIAL"X6S"
TOLERANCE"10%"
VALUE"1UF"
VOLTAGE"25V"
$LOCATION"C1289"
CDS_LIB"pure_quanta"
$LOCATION"C1289"
CDS_LOCATION"C1289"
$SEC"1"
CDS_SEC"1";
"B"
$PN"2"9;
"A"
$PN"1"4;
%"UNIVERSAL_POWER"
"1","(-9525,-1800)","0","logical_power","I111";
;
HDL_POWER"P3V3_AUX"
CDS_LIB"logical_power";
"A"4;
%"Q_CAP"
"1","(-9525,-2075)","2","pure_quanta","I112";
;
PART_NUMBER"CH4104K1B00"
TOLERANCE"10%"
VALUE"0.1UF"
VOLTAGE"25V"
PACK_TYPE"0402"
MATERIAL"X7R"
$LOCATION"C1288"
CDS_LIB"pure_quanta"
$LOCATION"C1288"
CDS_LOCATION"C1288"
$SEC"1"
CDS_SEC"1";
"B"
$PN"2"9;
"A"
$PN"1"4;
%"UNIVERSAL_GND"
"1","(-9525,-2375)","0","logical_power","I113";
;
HDL_POWER"GND"
CDS_LIB"logical_power";
"A"9;
%"Q_RES"
"2","(-9725,-2800)","0","pure_quanta","I116";
;
PART_NUMBER"CS21002FB06"
VALUE"1K"
TOLERANCE"1%"
MATERIAL"CHIP"
PACK_TYPE"0402LF"
WATTAGE"1/16W"
$LOCATION"R1365"
CDS_LIB"pure_quanta"
CDS_LOCATION"R1365"
$SEC"1"
CDS_SEC"1";
"A"
$PN"1"13;
"B"
$PN"2"8;
%"UNIVERSAL_GND"
"1","(-9725,-3000)","0","logical_power","I117";
;
CDS_LIB"logical_power"
HDL_POWER"GND";
"A"8;
%"UNIVERSAL_POWER"
"1","(-8175,-1000)","0","logical_power","I118";
;
HDL_POWER"P3V3_AUX"
CDS_LIB"logical_power";
"A"3;
%"74CBTLV3126PW"
"1","(-6025,-2450)","0","pure_quanta","I84";
;
PART_NUMBER"AL003126K08"
PART_TYPE"SMLF"
VALUE"74CBTLV3126PW"
MATERIAL"IC"
$LOCATION"U86"
CDS_LIB"pure_quanta"
NEEDS_NO_SIZE"TRUE"
CDS_LMAN_SYM_OUTLINE"-250,350,250,-350"
$LOCATION"U86"
CDS_LOCATION"U86"
$SEC"1"
CDS_SEC"1";
"VCC"
$PN"14"2;
"4OE"
$PN"13"16;
"4A"
$PN"12"18;
"4B"
$PN"11"25;
"3OE"
$PN"10"14;
"3A"
$PN"9"18;
"GND"
$PN"7"6;
"1A"
$PN"2"18;
"2B"
$PN"6"19;
"1B"
$PN"3"24;
"2OE"
$PN"4"15;
"1OE"
$PN"1"16;
"3B"
$PN"8"21;
"2A"
$PN"5"18;
%"Q_RES"
"1","(-4350,-2400)","0","pure_quanta","I87";
;
PART_NUMBER"CS00002JB13"
TOLERANCE"5%"
VALUE"0"
PACK_TYPE"0402LF"
MATERIAL"CHIP"
WATTAGE"1/16W"
$LOCATION"R1349"
CDS_LIB"pure_quanta"
$LOCATION"R1349"
CDS_LOCATION"R1349"
$SEC"1"
CDS_SEC"1";
"B"
$PN"2"22;
"A"
$PN"1"21;
%"Q_RES"
"1","(-4350,-2550)","0","pure_quanta","I88";
;
PART_NUMBER"CS00002JB13"
PACK_TYPE"0402LF"
VALUE"0"
TOLERANCE"5%"
$LOCATION"R1348"
CDS_LIB"pure_quanta"
MATERIAL"CHIP"
WATTAGE"1/16W"
$LOCATION"R1348"
CDS_LOCATION"R1348"
$SEC"1"
CDS_SEC"1";
"B"
$PN"2"20;
"A"
$PN"1"19;
%"UNIVERSAL_POWER"
"1","(-5475,-1600)","0","logical_power","I89";
;
HDL_POWER"P3V3_AUX"
CDS_LIB"logical_power";
"A"2;
%"Q_CAP"
"1","(-5275,-1950)","0","pure_quanta","I90";
;
PART_NUMBER"CH4104K1B00"
PACK_TYPE"0402"
VALUE"0.1UF"
VOLTAGE"25V"
MATERIAL"X7R"
TOLERANCE"10%"
$LOCATION"C1292"
CDS_LIB"pure_quanta"
$LOCATION"C1292"
CDS_LOCATION"C1292"
$SEC"1"
CDS_SEC"1";
"B"
$PN"2"7;
"A"
$PN"1"2;
%"UNIVERSAL_GND"
"1","(-5275,-2175)","0","logical_power","I91";
;
CDS_LIB"logical_power"
HDL_POWER"GND";
"A"7;
%"UNIVERSAL_GND"
"1","(-5475,-2950)","0","logical_power","I92";
;
CDS_LIB"logical_power"
HDL_POWER"GND";
"A"6;
%"UNIVERSAL_POWER"
"1","(-7225,-1125)","0","logical_power","I93";
;
HDL_POWER"P1V05_PCH_AUX"
CDS_LIB"logical_power";
"A"1;
%"UNIVERSAL_GND"
"1","(-7050,-2350)","0","logical_power","I94";
;
HDL_POWER"GND"
CDS_LIB"logical_power";
"A"5;
%"Q_CAP"
"1","(-7050,-2075)","0","pure_quanta","I95";
;
PART_NUMBER"CH5104KEB02"
PACK_TYPE"C0402"
VALUE"1UF"
MATERIAL"X6S"
VOLTAGE"25V"
TOLERANCE"10%"
$LOCATION"C1293"
CDS_LIB"pure_quanta"
CDS_LOCATION"C1293"
$SEC"1"
CDS_SEC"1";
"B"
$PN"2"5;
"A"
$PN"1"18;
%"MOSFET_N"
"1","(-7275,-1375)","0","pure_quanta","I96";
;
PART_NUMBER"BAM138K0000"
MATERIAL"IC"
VALUE"BSS138K"
$LOCATION"U87"
MANUF_PN"BSS138K"
PACK_TYPE"SMLF"
CDS_LIB"pure_quanta"
CDS_LMAN_SYM_OUTLINE"-50,50,100,-150"
CDS_LOCATION"U87"
$SEC"1"
CDS_SEC"1";
"GATE"
$PN"G"17;
"SOURCE"
$PN"S"18;
"DRAIN"
$PN"D"1;
%"Q_RES"
"2","(-7225,-2075)","2","pure_quanta","I97";
;
PART_NUMBER"CS31002FB08"
TOLERANCE"1%"
PACK_TYPE"0402LF"
MATERIAL"CHIP"
WATTAGE"1/16W"
VALUE"10K"
$LOCATION"R1375"
CDS_LIB"pure_quanta"
CDS_LOCATION"R1375"
$SEC"1"
CDS_SEC"1";
"A"
$PN"1"18;
"B"
$PN"2"5;
%"Q_RES"
"2","(-8175,-1250)","2","pure_quanta","I98";
;
PART_NUMBER"CS11002FB07"
WATTAGE"1/16W"
VALUE"100"
TOLERANCE"1%"
PACK_TYPE"0402LF"
MATERIAL"CHIP"
$LOCATION"R1370"
CDS_LIB"pure_quanta"
CDS_LOCATION"R1370"
$SEC"1"
CDS_SEC"1";
"A"
$PN"1"3;
"B"
$PN"2"17;
END.
